(kicad_pcb
	(version 20241229)
	(generator "pcbnew")
	(generator_version "9.0")
	(general
		(thickness 1.711)
		(legacy_teardrops no)
	)
	(paper "A4")
	(title_block
		(title "Antmicro Baseboard for Jetson AGX Thor")
		(date "2026-02-18")
		(rev "1.1.0")
		(company "Antmicro Ltd")
		(comment 1 "www.antmicro.com")
		(comment 9 "footprints 883-886 of 1170")
	)
	(layers
		(0 "F.Cu" signal)
		(4 "In1.Cu" signal)
		(6 "In2.Cu" signal)
		(8 "In3.Cu" signal)
		(10 "In4.Cu" jumper)
		(12 "In5.Cu" signal)
		(14 "In6.Cu" signal)
		(16 "In7.Cu" signal)
		(18 "In8.Cu" signal)
		(2 "B.Cu" signal)
		(9 "F.Adhes" user "F.Adhesive")
		(11 "B.Adhes" user "B.Adhesive")
		(13 "F.Paste" user)
		(15 "B.Paste" user)
		(5 "F.SilkS" user "F.Silkscreen")
		(7 "B.SilkS" user "B.Silkscreen")
		(1 "F.Mask" user)
		(3 "B.Mask" user)
		(17 "Dwgs.User" user "User.Drawings")
		(19 "Cmts.User" user "User.Comments")
		(21 "Eco1.User" user "User.Eco1")
		(23 "Eco2.User" user "User.Eco2")
		(25 "Edge.Cuts" user)
		(27 "Margin" user)
		(31 "F.CrtYd" user "F.Courtyard")
		(29 "B.CrtYd" user "B.Courtyard")
		(35 "F.Fab" user)
		(33 "B.Fab" user)
	)
	(footprint "antmicro-footprints:Spacer_Drill3.7mm_H8mm_9774080151R"
		(locked yes)
		(layer "B.Cu")
		(at 152.430532 63.71 180)
		(descr "Spacer M=3 h=8mm fi=5.1mm")
		(property "Reference" "H11"
			(at 0 3.2 0)
			(layer "B.SilkS")
			(effects
				(font
					(size 0.7 0.7)
					(thickness 0.15)
				)
				(justify left bottom mirror)
			)
		)
		(property "Value" "Spacer_Drill3.7mm_H8mm_9774080151R"
			(at 0 -4 0)
			(layer "B.Fab")
			(effects
				(font
					(size 0.7 0.7)
					(thickness 0.15)
				)
				(justify left bottom mirror)
			)
		)
		(property "Datasheet" "https://www.we-online.com/components/products/datasheet/9774080151R.pdf"
			(at 0 0 0)
			(layer "B.Fab")
			(hide yes)
			(effects
				(font
					(size 1.27 1.27)
					(thickness 0.15)
				)
				(justify mirror)
			)
		)
		(property "Description" "Spacer, SMT, Non Stop, Steel, Swage Round, 5.1 mm x 8 mm, M2.5 Thread, WA-SMSI Series"
			(at 0 0 0)
			(layer "B.Fab")
			(hide yes)
			(effects
				(font
					(size 1.27 1.27)
					(thickness 0.15)
				)
				(justify mirror)
			)
		)
		(property "Manufacturer" "Würth Elektronik"
			(at 0 0 180)
			(unlocked yes)
			(layer "B.Fab")
			(hide yes)
			(effects
				(font
					(size 1 1)
					(thickness 0.15)
				)
				(justify mirror)
			)
		)
		(property "MPN" "9774080151R"
			(at 0 0 180)
			(unlocked yes)
			(layer "B.Fab")
			(hide yes)
			(effects
				(font
					(size 1 1)
					(thickness 0.15)
				)
				(justify mirror)
			)
		)
		(property "Author" "Antmicro"
			(at 0 0 180)
			(unlocked yes)
			(layer "B.Fab")
			(hide yes)
			(effects
				(font
					(size 1 1)
					(thickness 0.15)
				)
				(justify mirror)
			)
		)
		(property "License" "Apache-2.0"
			(at 0 0 180)
			(unlocked yes)
			(layer "B.Fab")
			(hide yes)
			(effects
				(font
					(size 1 1)
					(thickness 0.15)
				)
				(justify mirror)
			)
		)
		(sheetname "/")
		(sheetfile "jetson-agx-thor-baseboard.kicad_sch")
		(solder_paste_margin_ratio -1)
		(attr smd)
		(fp_circle
			(center 0 0)
			(end 3.05 0)
			(stroke
				(width 0.05)
				(type solid)
			)
			(fill no)
			(layer "B.CrtYd")
		)
		(fp_circle
			(center 0 0)
			(end 2.6 0)
			(stroke
				(width 0.15)
				(type solid)
			)
			(fill no)
			(layer "B.Fab")
		)
		(fp_text user "Author: Antmicro"
			(at -9.6 -7.7 0)
			(layer "B.Fab")
			(effects
				(font
					(size 0.7 0.7)
					(thickness 0.15)
				)
				(justify left bottom mirror)
			)
		)
		(fp_text user "License: Apache-2.0"
			(at -9.6 -8.9 0)
			(layer "B.Fab")
			(effects
				(font
					(size 0.7 0.7)
					(thickness 0.15)
				)
				(justify left bottom mirror)
			)
		)
		(fp_text user "${REFERENCE}"
			(at -9.6 -6.5 0)
			(layer "B.Fab")
			(effects
				(font
					(size 0.7 0.7)
					(thickness 0.15)
				)
				(justify left bottom mirror)
			)
		)
		(pad "" smd custom
			(at -1.7 -1.7 90)
			(size 0.62 0.62)
			(layers "B.Paste")
			(thermal_bridge_angle 90)
			(options
				(clearance outline)
				(anchor circle)
			)
			(primitives
				(gr_arc
					(start 1.266786 0.24747)
					(mid 0.285453 -0.29439)
					(end -0.250195 -1.279127)
					(width 0.2)
				)
				(gr_arc
					(start 1.259603 0.339191)
					(mid 0.218448 -0.232561)
					(end -0.34334 -1.279127)
					(width 0.2)
				)
				(gr_arc
					(start 1.255279 0.431435)
					(mid 0.152481 -0.169693)
					(end -0.436309 -1.279127)
					(width 0.2)
				)
				(gr_arc
					(start 1.253811 0.524161)
					(mid 0.087542 -0.105784)
					(end -0.529126 -1.279127)
					(width 0.2)
				)
				(gr_arc
					(start 1.275473 0.621136)
					(mid 0.0309 -0.033527)
					(end -0.621807 -1.279127)
					(width 0.2)
				)
				(gr_arc
					(start 1.263664 0.711602)
					(mid -0.037759 0.026651)
					(end -0.71437 -1.279127)
					(width 0.2)
				)
				(gr_arc
					(start 1.253435 0.802342)
					(mid -0.105837 0.087395)
					(end -0.806826 -1.279127)
					(width 0.2)
				)
				(gr_arc
					(start 1.267475 0.897258)
					(mid -0.165236 0.156885)
					(end -0.899187 -1.279127)
					(width 0.2)
				)
				(gr_arc
					(start 1.270645 0.990112)
					(mid -0.228522 0.222449)
					(end -0.991463 -1.279127)
					(width 0.2)
				)
				(gr_arc
					(start 1.266278 1.081674)
					(mid -0.294507 0.285313)
					(end -1.083663 -1.279127)
					(width 0.2)
				)
				(gr_line
					(start 1.279127 0.250195)
					(end 1.279127 1.083663)
					(width 0.2)
				)
				(gr_line
					(start -0.250195 -1.279127)
					(end -1.083663 -1.279127)
					(width 0.2)
				)
			)
		)
		(pad "" smd custom
			(at -1.7 1.7 180)
			(size 0.62 0.62)
			(layers "B.Paste")
			(thermal_bridge_angle 90)
			(options
				(clearance outline)
				(anchor circle)
			)
			(primitives
				(gr_arc
					(start 1.266786 0.24747)
					(mid 0.285453 -0.29439)
					(end -0.250195 -1.279127)
					(width 0.2)
				)
				(gr_arc
					(start 1.259603 0.339191)
					(mid 0.218448 -0.232561)
					(end -0.34334 -1.279127)
					(width 0.2)
				)
				(gr_arc
					(start 1.255279 0.431435)
					(mid 0.152481 -0.169693)
					(end -0.436309 -1.279127)
					(width 0.2)
				)
				(gr_arc
					(start 1.253811 0.524161)
					(mid 0.087542 -0.105784)
					(end -0.529126 -1.279127)
					(width 0.2)
				)
				(gr_arc
					(start 1.275473 0.621136)
					(mid 0.0309 -0.033527)
					(end -0.621807 -1.279127)
					(width 0.2)
				)
				(gr_arc
					(start 1.263664 0.711602)
					(mid -0.037759 0.026651)
					(end -0.71437 -1.279127)
					(width 0.2)
				)
				(gr_arc
					(start 1.253435 0.802342)
					(mid -0.105837 0.087395)
					(end -0.806826 -1.279127)
					(width 0.2)
				)
				(gr_arc
					(start 1.267475 0.897258)
					(mid -0.165236 0.156885)
					(end -0.899187 -1.279127)
					(width 0.2)
				)
				(gr_arc
					(start 1.270645 0.990112)
					(mid -0.228522 0.222449)
					(end -0.991463 -1.279127)
					(width 0.2)
				)
				(gr_arc
					(start 1.266278 1.081674)
					(mid -0.294507 0.285313)
					(end -1.083663 -1.279127)
					(width 0.2)
				)
				(gr_line
					(start 1.279127 0.250195)
					(end 1.279127 1.083663)
					(width 0.2)
				)
				(gr_line
					(start -0.250195 -1.279127)
					(end -1.083663 -1.279127)
					(width 0.2)
				)
			)
		)
		(pad "" smd custom
			(at 1.7 -1.7)
			(size 0.62 0.62)
			(layers "B.Paste")
			(thermal_bridge_angle 90)
			(options
				(clearance outline)
				(anchor circle)
			)
			(primitives
				(gr_arc
					(start 1.266786 0.24747)
					(mid 0.285453 -0.29439)
					(end -0.250195 -1.279127)
					(width 0.2)
				)
				(gr_arc
					(start 1.259603 0.339191)
					(mid 0.218448 -0.232561)
					(end -0.34334 -1.279127)
					(width 0.2)
				)
				(gr_arc
					(start 1.255279 0.431435)
					(mid 0.152481 -0.169693)
					(end -0.436309 -1.279127)
					(width 0.2)
				)
				(gr_arc
					(start 1.253811 0.524161)
					(mid 0.087542 -0.105784)
					(end -0.529126 -1.279127)
					(width 0.2)
				)
				(gr_arc
					(start 1.275473 0.621136)
					(mid 0.0309 -0.033527)
					(end -0.621807 -1.279127)
					(width 0.2)
				)
				(gr_arc
					(start 1.263664 0.711602)
					(mid -0.037759 0.026651)
					(end -0.71437 -1.279127)
					(width 0.2)
				)
				(gr_arc
					(start 1.253435 0.802342)
					(mid -0.105837 0.087395)
					(end -0.806826 -1.279127)
					(width 0.2)
				)
				(gr_arc
					(start 1.267475 0.897258)
					(mid -0.165236 0.156885)
					(end -0.899187 -1.279127)
					(width 0.2)
				)
				(gr_arc
					(start 1.270645 0.990112)
					(mid -0.228522 0.222449)
					(end -0.991463 -1.279127)
					(width 0.2)
				)
				(gr_arc
					(start 1.266278 1.081674)
					(mid -0.294507 0.285313)
					(end -1.083663 -1.279127)
					(width 0.2)
				)
				(gr_line
					(start 1.279127 0.250195)
					(end 1.279127 1.083663)
					(width 0.2)
				)
				(gr_line
					(start -0.250195 -1.279127)
					(end -1.083663 -1.279127)
					(width 0.2)
				)
			)
		)
		(pad "" smd custom
			(at 1.7 1.7 270)
			(size 0.62 0.62)
			(layers "B.Paste")
			(thermal_bridge_angle 90)
			(options
				(clearance outline)
				(anchor circle)
			)
			(primitives
				(gr_arc
					(start 1.266786 0.24747)
					(mid 0.285453 -0.29439)
					(end -0.250195 -1.279127)
					(width 0.2)
				)
				(gr_arc
					(start 1.259603 0.339191)
					(mid 0.218448 -0.232561)
					(end -0.34334 -1.279127)
					(width 0.2)
				)
				(gr_arc
					(start 1.255279 0.431435)
					(mid 0.152481 -0.169693)
					(end -0.436309 -1.279127)
					(width 0.2)
				)
				(gr_arc
					(start 1.253811 0.524161)
					(mid 0.087542 -0.105784)
					(end -0.529126 -1.279127)
					(width 0.2)
				)
				(gr_arc
					(start 1.275473 0.621136)
					(mid 0.0309 -0.033527)
					(end -0.621807 -1.279127)
					(width 0.2)
				)
				(gr_arc
					(start 1.263664 0.711602)
					(mid -0.037759 0.026651)
					(end -0.71437 -1.279127)
					(width 0.2)
				)
				(gr_arc
					(start 1.253435 0.802342)
					(mid -0.105837 0.087395)
					(end -0.806826 -1.279127)
					(width 0.2)
				)
				(gr_arc
					(start 1.267475 0.897258)
					(mid -0.165236 0.156885)
					(end -0.899187 -1.279127)
					(width 0.2)
				)
				(gr_arc
					(start 1.270645 0.990112)
					(mid -0.228522 0.222449)
					(end -0.991463 -1.279127)
					(width 0.2)
				)
				(gr_arc
					(start 1.266278 1.081674)
					(mid -0.294507 0.285313)
					(end -1.083663 -1.279127)
					(width 0.2)
				)
				(gr_line
					(start 1.279127 0.250195)
					(end 1.279127 1.083663)
					(width 0.2)
				)
				(gr_line
					(start -0.250195 -1.279127)
					(end -1.083663 -1.279127)
					(width 0.2)
				)
			)
		)
		(pad "1" thru_hole circle
			(at 0 0 180)
			(size 6 6)
			(drill 3.7)
			(layers "*.Cu" "*.Mask")
			(remove_unused_layers no)
			(net 1 "GND")
			(pintype "passive")
		)
	)
	(footprint "antmicro-footprints:R_0402_1005Metric"
		(layer "B.Cu")
		(at 238.579002 93.424001)
		(descr "Resistor SMD 0402")
		(tags "resistor SMD 0402")
		(property "Reference" "R142"
			(at -1.579002 -2.624001 0)
			(layer "B.SilkS")
			(effects
				(font
					(size 0.7 0.7)
					(thickness 0.15)
				)
				(justify right top mirror)
			)
		)
		(property "Value" "R_0R_0402"
			(at -1.011843 -1.772046 0)
			(layer "B.Fab")
			(effects
				(font
					(size 0.7 0.7)
					(thickness 0.15)
				)
				(justify right top mirror)
			)
		)
		(property "Datasheet" "https://industrial.panasonic.com/cdbs/www-data/pdf/RDA0000/AOA0000C301.pdf"
			(at 0 0 0)
			(layer "B.Fab")
			(hide yes)
			(effects
				(font
					(size 1.27 1.27)
					(thickness 0.15)
				)
				(justify mirror)
			)
		)
		(property "Description" "SMD Chip Resistor, Jumper, 0 ohm, 100 mW, 0402 [1005 Metric], Thick Film, General Purpose"
			(at 0 0 0)
			(layer "B.Fab")
			(hide yes)
			(effects
				(font
					(size 1.27 1.27)
					(thickness 0.15)
				)
				(justify mirror)
			)
		)
		(property "Manufacturer" "Panasonic"
			(at 0 0 180)
			(unlocked yes)
			(layer "B.Fab")
			(hide yes)
			(effects
				(font
					(size 1 1)
					(thickness 0.15)
				)
				(justify mirror)
			)
		)
		(property "MPN" "ERJ2GE0R00X"
			(at 0 0 180)
			(unlocked yes)
			(layer "B.Fab")
			(hide yes)
			(effects
				(font
					(size 1 1)
					(thickness 0.15)
				)
				(justify mirror)
			)
		)
		(property "Val" "0R"
			(at 0 0 180)
			(unlocked yes)
			(layer "B.Fab")
			(hide yes)
			(effects
				(font
					(size 1 1)
					(thickness 0.15)
				)
				(justify mirror)
			)
		)
		(property "License" "Apache-2.0"
			(at 0 0 180)
			(unlocked yes)
			(layer "B.Fab")
			(hide yes)
			(effects
				(font
					(size 1 1)
					(thickness 0.15)
				)
				(justify mirror)
			)
		)
		(property "Author" "Antmicro"
			(at 0 0 180)
			(unlocked yes)
			(layer "B.Fab")
			(hide yes)
			(effects
				(font
					(size 1 1)
					(thickness 0.15)
				)
				(justify mirror)
			)
		)
		(property "Tolerance" "~"
			(at 0 0 180)
			(unlocked yes)
			(layer "B.Fab")
			(hide yes)
			(effects
				(font
					(size 1 1)
					(thickness 0.15)
				)
				(justify mirror)
			)
		)
		(property "Current" "1A"
			(at 0 0 180)
			(unlocked yes)
			(layer "B.Fab")
			(hide yes)
			(effects
				(font
					(size 1 1)
					(thickness 0.15)
				)
				(justify mirror)
			)
		)
		(sheetname "/USB DP Alt mode/")
		(sheetfile "usb_dp.kicad_sch")
		(attr smd exclude_from_pos_files exclude_from_bom dnp)
		(fp_poly
			(pts
				(xy -0.925 0.47) (xy -0.925 -0.47) (xy 0.925 -0.47) (xy 0.925 0.47)
			)
			(stroke
				(width 0.05)
				(type default)
			)
			(fill no)
			(layer "B.CrtYd")
		)
		(fp_poly
			(pts
				(xy -0.5 0.25) (xy -0.5 -0.25) (xy 0.5 -0.25) (xy 0.5 0.25)
			)
			(stroke
				(width 0.15)
				(type solid)
			)
			(fill no)
			(layer "B.Fab")
		)
		(fp_text user "License: Apache-2.0"
			(at -0.949999 -5.169 0)
			(layer "B.Fab")
			(effects
				(font
					(size 0.7 0.7)
					(thickness 0.15)
				)
				(justify right top mirror)
			)
		)
		(fp_text user "${REFERENCE}"
			(at -0.95 -3.168 0)
			(layer "B.Fab")
			(effects
				(font
					(size 0.7 0.7)
					(thickness 0.15)
				)
				(justify right top mirror)
			)
		)
		(fp_text user "Author: Antmicro"
			(at -0.95 -4.169 0)
			(layer "B.Fab")
			(effects
				(font
					(size 0.7 0.7)
					(thickness 0.15)
				)
				(justify right top mirror)
			)
		)
		(pad "1" smd roundrect
			(at -0.48 0)
			(size 0.59 0.64)
			(layers "B.Cu" "B.Mask" "B.Paste")
			(roundrect_rratio 0.25)
			(net 970 "/USB DP Alt mode/USBC1_5V_PEN")
			(pintype "passive")
		)
		(pad "2" smd roundrect
			(at 0.48 0)
			(size 0.59 0.64)
			(layers "B.Cu" "B.Mask" "B.Paste")
			(roundrect_rratio 0.25)
			(net 5 "+5V")
			(pintype "passive")
		)
	)
	(footprint "antmicro-footprints:TP_SMD_0.75mm"
		(layer "B.Cu")
		(at 127.4 152.2 -90)
		(property "Reference" "TP96"
			(at 0.4 0.6 0)
			(layer "B.SilkS")
			(effects
				(font
					(size 0.7 0.7)
					(thickness 0.15)
				)
				(justify left bottom mirror)
			)
		)
		(property "Value" "TP_0.75mm_SMD"
			(at 0 -1.2 90)
			(layer "B.Fab")
			(effects
				(font
					(size 0.7 0.7)
					(thickness 0.15)
				)
				(justify left bottom mirror)
			)
		)
		(property "Description" "SMT test point"
			(at 0 0 90)
			(layer "B.Fab")
			(hide yes)
			(effects
				(font
					(size 1.27 1.27)
					(thickness 0.15)
				)
				(justify mirror)
			)
		)
		(property "MPN" ""
			(at 0 0 90)
			(unlocked yes)
			(layer "B.Fab")
			(hide yes)
			(effects
				(font
					(size 1 1)
					(thickness 0.15)
				)
				(justify mirror)
			)
		)
		(property "Manufacturer" ""
			(at 0 0 90)
			(unlocked yes)
			(layer "B.Fab")
			(hide yes)
			(effects
				(font
					(size 1 1)
					(thickness 0.15)
				)
				(justify mirror)
			)
		)
		(property "Author" "Antmicro"
			(at 0 0 90)
			(unlocked yes)
			(layer "B.Fab")
			(hide yes)
			(effects
				(font
					(size 1 1)
					(thickness 0.15)
				)
				(justify mirror)
			)
		)
		(property "License" "Apache-2.0"
			(at 0 0 90)
			(unlocked yes)
			(layer "B.Fab")
			(hide yes)
			(effects
				(font
					(size 1 1)
					(thickness 0.15)
				)
				(justify mirror)
			)
		)
		(sheetname "/Peripherals/")
		(sheetfile "peripherals.kicad_sch")
		(attr exclude_from_pos_files exclude_from_bom)
		(fp_circle
			(center 0 0)
			(end 0.475 0)
			(stroke
				(width 0.05)
				(type default)
			)
			(fill no)
			(layer "B.CrtYd")
		)
		(fp_text user "Author: Antmicro"
			(at -0.4 -3.901 90)
			(layer "B.Fab")
			(effects
				(font
					(size 0.7 0.7)
					(thickness 0.15)
				)
				(justify left bottom mirror)
			)
		)
		(fp_text user "${REFERENCE}"
			(at -0.4 -2.7 90)
			(layer "B.Fab")
			(effects
				(font
					(size 0.7 0.7)
					(thickness 0.15)
				)
				(justify left bottom mirror)
			)
		)
		(fp_text user "License: Apache-2.0"
			(at -0.4 -5.101 90)
			(layer "B.Fab")
			(effects
				(font
					(size 0.7 0.7)
					(thickness 0.15)
				)
				(justify left bottom mirror)
			)
		)
		(pad "1" smd circle
			(at 0 0 270)
			(size 0.75 0.75)
			(layers "B.Cu" "B.Mask")
			(net 149 "/Peripherals/TPM_IRQ")
			(pinfunction "1")
			(pintype "passive")
		)
	)
	(footprint "antmicro-footprints:C_0603_1608Metric_EIA"
		(layer "B.Cu")
		(at 124.6 121.44 180)
		(descr "Capacitor SMD 0603, IPC-7351 Density Level A")
		(tags "Capacitor 0603")
		(property "Reference" "C74"
			(at -3.47 -0.415 0)
			(layer "B.SilkS")
			(effects
				(font
					(size 0.7 0.7)
					(thickness 0.15)
				)
				(justify left bottom mirror)
			)
		)
		(property "Value" "C_22u_16V_0603"
			(at -1.42757 -1.770288 0)
			(layer "B.Fab")
			(effects
				(font
					(size 0.7 0.7)
					(thickness 0.15)
				)
				(justify left bottom mirror)
			)
		)
		(property "Datasheet" "https://product.samsungsem.com/mlcc/CL10A226MO7JZN.do"
			(at 0 0 0)
			(layer "B.Fab")
			(hide yes)
			(effects
				(font
					(size 1.27 1.27)
					(thickness 0.15)
				)
				(justify mirror)
			)
		)
		(property "Description" "SMD Multilayer Ceramic Capacitor"
			(at 0 0 0)
			(layer "B.Fab")
			(hide yes)
			(effects
				(font
					(size 1.27 1.27)
					(thickness 0.15)
				)
				(justify mirror)
			)
		)
		(property "MPN" "CL10A226MO7JZNC"
			(at 0 0 180)
			(unlocked yes)
			(layer "B.Fab")
			(hide yes)
			(effects
				(font
					(size 1 1)
					(thickness 0.15)
				)
				(justify mirror)
			)
		)
		(property "Manufacturer" "Samsung Electro-Mechanics"
			(at 0 0 180)
			(unlocked yes)
			(layer "B.Fab")
			(hide yes)
			(effects
				(font
					(size 1 1)
					(thickness 0.15)
				)
				(justify mirror)
			)
		)
		(property "License" "Apache-2.0"
			(at 0 0 180)
			(unlocked yes)
			(layer "B.Fab")
			(hide yes)
			(effects
				(font
					(size 1 1)
					(thickness 0.15)
				)
				(justify mirror)
			)
		)
		(property "Author" "Antmicro"
			(at 0 0 180)
			(unlocked yes)
			(layer "B.Fab")
			(hide yes)
			(effects
				(font
					(size 1 1)
					(thickness 0.15)
				)
				(justify mirror)
			)
		)
		(property "Val" "22u"
			(at 0 0 180)
			(unlocked yes)
			(layer "B.Fab")
			(hide yes)
			(effects
				(font
					(size 1 1)
					(thickness 0.15)
				)
				(justify mirror)
			)
		)
		(property "Voltage" "16V"
			(at 0 0 180)
			(unlocked yes)
			(layer "B.Fab")
			(hide yes)
			(effects
				(font
					(size 1 1)
					(thickness 0.15)
				)
				(justify mirror)
			)
		)
		(property "Dielectric" ""
			(at 0 0 180)
			(unlocked yes)
			(layer "B.Fab")
			(hide yes)
			(effects
				(font
					(size 1 1)
					(thickness 0.15)
				)
				(justify mirror)
			)
		)
		(sheetname "/M.2/")
		(sheetfile "m2.kicad_sch")
		(attr smd)
		(fp_line
			(start -0.15 0.55)
			(end 0.15 0.55)
			(stroke
				(width 0.15)
				(type solid)
			)
			(layer "B.SilkS")
		)
		(fp_line
			(start -0.15 -0.55)
			(end 0.15 -0.55)
			(stroke
				(width 0.15)
				(type solid)
			)
			(layer "B.SilkS")
		)
		(fp_rect
			(start -1.25 0.65)
			(end 1.25 -0.65)
			(stroke
				(width 0.05)
				(type solid)
			)
			(fill no)
			(layer "B.CrtYd")
		)
		(fp_rect
			(start -0.8 0.45)
			(end 0.8 -0.45)
			(stroke
				(width 0.15)
				(type solid)
			)
			(fill no)
			(layer "B.Fab")
		)
		(fp_text user "${REFERENCE}"
			(at -1.682 -3.895 0)
			(layer "B.Fab")
			(effects
				(font
					(size 0.7 0.7)
					(thickness 0.15)
				)
				(justify left bottom mirror)
			)
		)
		(fp_text user "Author: Antmicro"
			(at -1.682 -4.894 0)
			(layer "B.Fab")
			(effects
				(font
					(size 0.7 0.7)
					(thickness 0.15)
				)
				(justify left bottom mirror)
			)
		)
		(fp_text user "License: Apache-2.0"
			(at -1.682 -5.895 0)
			(layer "B.Fab")
			(effects
				(font
					(size 0.7 0.7)
					(thickness 0.15)
				)
				(justify left bottom mirror)
			)
		)
		(pad "1" smd roundrect
			(at -0.7 0 180)
			(size 0.8 1.1)
			(layers "B.Cu" "B.Mask" "B.Paste")
			(roundrect_rratio 0.2)
			(net 1 "GND")
			(pintype "passive")
		)
		(pad "2" smd roundrect
			(at 0.7 0 180)
			(size 0.8 1.1)
			(layers "B.Cu" "B.Mask" "B.Paste")
			(roundrect_rratio 0.2)
			(net 2 "+3V3")
			(pintype "passive")
		)
	)
)
